#ISCELL
  mstr_misc dns *
  *
#ISCELL
  pure_quanta quanta_title_block_c *
  *
#CELL
  pure_quanta q_res *
  page80_i1
#ISCELL
  logical_power universal_power *
  page80_i10
#ISCELL
  logical_power universal_power *
  page80_i11
#CELL
  pure_quanta q_res *
  page80_i12
#CELL
  pure_quanta q_res *
  page80_i13
#ISCELL
  standard offpage *
  page80_i14
#ISCELL
  standard offpage *
  page80_i15
#ISCELL
  standard offpage *
  page80_i16
#ISCELL
  standard offpage *
  page80_i17
#ISCELL
  logical_power universal_power *
  page80_i18
#ISCELL
  logical_power universal_gnd *
  page80_i19
#CELL
  pure_quanta q_res *
  page80_i2
#CELL
  pure_quanta q_cap *
  page80_i20
#ISCELL
  logical_power universal_power *
  page80_i21
#CELL
  pure_quanta q_res *
  page80_i22
#ISCELL
  standard offpage *
  page80_i23
#ISCELL
  standard offpage *
  page80_i24
#CELL
  pure_quanta q_res *
  page80_i25
#CELL
  pure_quanta q_res *
  page80_i26
#CELL
  pure_quanta q_res *
  page80_i27
#CELL
  pure_quanta q_cap *
  page80_i28
#ISCELL
  standard offpage *
  page80_i29
#ISCELL
  logical_power universal_power *
  page80_i3
#ISCELL
  standard offpage *
  page80_i30
#ISCELL
  logical_power universal_power *
  page80_i31
#ISCELL
  logical_power universal_power *
  page80_i32
#ISCELL
  logical_power universal_power *
  page80_i33
#CELL
  pure_quanta q_res *
  page80_i34
#CELL
  pure_quanta q_res *
  page80_i35
#ISCELL
  logical_power universal_power *
  page80_i36
#ISCELL
  logical_power universal_gnd *
  page80_i4
#CELL
  pure_quanta q_cap *
  page80_i5
#ISCELL
  logical_power universal_power *
  page80_i6
#CELL
  pure_quanta q_res *
  page80_i7
#CELL
  pure_quanta q_res *
  page80_i8
#CELL
  pure_quanta q_cap *
  page80_i9
